# S9S_MB_2U (Grand Teton) — schematic netlist excerpt (pin names and nets, part order shuffled) for the footprints in the layout excerpt that follows; sources: Cadence DE-HDL packaged netlist, KiCad conversion of 03242023_DA0F0TMBIJ0_F0T_Motherboard_J_brd_V01_OCP.brd

D67  Q_LED  IC  pkg SMLF  page 256 : A = LED_RST_PLD_CPU0_DRAM_EF_N ; C = LED_RST_PLD_CPU0_DRAM_EF_N_D
R674  Q_RES  0 5% CHIP  pkg 0402LF  page 230 : A = I3C_SPD_DDRABCD_CPU1_LVC1_R_SCL ; B = I3C_SPD_DDRABCD_CPU1_LVC1_SCL
C1565  Q_CAP_DIFFBUS  DIFF BUS_0.22UF 6.3V 20% X6S  pkg C0201  page 175 : \1\ = P5E_CPU0_PE4_TX_C_DP<7> ; \2\ = P5E_CPU0_PE4_TX_DP<7>

(kicad_pcb
	(version 20260206)
	(generator "pcbnew")
	(generator_version "10.0")
	(general
		(thickness 1.6)
		(legacy_teardrops no)
	)
	(paper "A4")
	(title_block
		(title "03242023_DA0F0TMBIJ0_F0T_Motherboard_J_brd_V01_OCP.brd")
		(comment 1 "Grand Teton / footprints 2859-2861 of 6105")
	)
	(layers
		(0 "F.Cu" signal "TOP")
		(4 "In1.Cu" signal "GND")
		(6 "In2.Cu" signal "IN1")
		(8 "In3.Cu" signal "GND1")
		(10 "In4.Cu" signal "IN2")
		(12 "In5.Cu" signal "GND2")
		(14 "In6.Cu" signal "IN3")
		(16 "In7.Cu" signal "GND3")
		(18 "In8.Cu" signal "VCC")
		(20 "In9.Cu" signal "VCC1")
		(22 "In10.Cu" signal "GND4")
		(24 "In11.Cu" signal "IN4")
		(26 "In12.Cu" signal "GND5")
		(28 "In13.Cu" signal "IN5")
		(30 "In14.Cu" signal "GND6")
		(32 "In15.Cu" signal "IN6")
		(34 "In16.Cu" signal "GND7")
		(2 "B.Cu" signal "BOTTOM")
		(9 "F.Adhes" user "F.Adhesive")
		(11 "B.Adhes" user "B.Adhesive")
		(13 "F.Paste" user "Package Geometry/Pastemask Top")
		(15 "B.Paste" user "Package Geometry/Pastemask Bottom")
		(5 "F.SilkS" user "Ref Des/Silkscreen Top")
		(7 "B.SilkS" user "Ref Des/Silkscreen Bottom")
		(1 "F.Mask" user "Board Geometry/Soldermask Top")
		(3 "B.Mask" user "Board Geometry/Soldermask Bottom")
		(17 "Dwgs.User" user "User.Drawings")
		(19 "Cmts.User" user "User.Comments")
		(21 "Eco1.User" user "User.Eco1")
		(23 "Eco2.User" user "User.Eco2")
		(25 "Edge.Cuts" user "Board Geometry/Outline")
		(27 "Margin" user)
		(31 "F.CrtYd" user "Package Geometry/Place Bound Top")
		(29 "B.CrtYd" user "Package Geometry/Place Bound Bottom")
		(35 "F.Fab" user "Ref Des/Assembly Top")
		(33 "B.Fab" user "Ref Des/Assembly Bottom")
	)
	(footprint ""
		(layer "F.Cu")
		(at 74.580496 -70.78599)
		(property "Reference" "D67"
			(at -38.897306 50.178462 90)
			(unlocked yes)
			(layer "F.SilkS")
			(effects
				(font
					(size 0.635 0.4064)
					(thickness 0.1524)
				)
				(justify left)
			)
		)
		(property "Value" ""
			(at 0 0 0)
			(layer "F.Fab")
			(effects
				(font
					(size 1.27 1.27)
				)
			)
		)
		(duplicate_pad_numbers_are_jumpers no)
		(fp_line
			(start -0.90678 0.4826)
			(end -0.90678 -0.4699)
			(stroke
				(width 0.1524)
				(type default)
			)
			(layer "F.SilkS")
		)
		(fp_line
			(start -0.89408 -0.4826)
			(end 0.90678 -0.4826)
			(stroke
				(width 0.1524)
				(type default)
			)
			(layer "F.SilkS")
		)
		(fp_line
			(start -0.79248 -0.4826)
			(end 1.03378 -0.4826)
			(stroke
				(width 0.1524)
				(type default)
			)
			(layer "F.SilkS")
		)
		(fp_line
			(start -0.64008 -0.4826)
			(end 1.16078 -0.4826)
			(stroke
				(width 0.1524)
				(type default)
			)
			(layer "F.SilkS")
		)
		(fp_line
			(start 0.90678 -0.4826)
			(end 0.90678 0.4826)
			(stroke
				(width 0.1524)
				(type default)
			)
			(layer "F.SilkS")
		)
		(fp_line
			(start 0.90678 0.4826)
			(end -0.90678 0.4826)
			(stroke
				(width 0.1524)
				(type default)
			)
			(layer "F.SilkS")
		)
		(fp_line
			(start 1.03378 -0.4826)
			(end 1.03378 0.4826)
			(stroke
				(width 0.1524)
				(type default)
			)
			(layer "F.SilkS")
		)
		(fp_line
			(start 1.03378 0.4826)
			(end -0.79248 0.4826)
			(stroke
				(width 0.1524)
				(type default)
			)
			(layer "F.SilkS")
		)
		(fp_line
			(start 1.16078 -0.4826)
			(end 1.16078 0.4826)
			(stroke
				(width 0.1524)
				(type default)
			)
			(layer "F.SilkS")
		)
		(fp_line
			(start 1.16078 0.4826)
			(end -0.64008 0.4826)
			(stroke
				(width 0.1524)
				(type default)
			)
			(layer "F.SilkS")
		)
		(fp_line
			(start -0.499872 -0.249936)
			(end 0.499872 -0.249936)
			(stroke
				(width 0.1)
				(type default)
			)
			(layer "F.Fab")
		)
		(fp_line
			(start -0.499872 0.249936)
			(end -0.499872 -0.249936)
			(stroke
				(width 0.1)
				(type default)
			)
			(layer "F.Fab")
		)
		(fp_line
			(start 0.499872 -0.249936)
			(end 0.499872 0.249936)
			(stroke
				(width 0.1)
				(type default)
			)
			(layer "F.Fab")
		)
		(fp_line
			(start 0.499872 0.249936)
			(end -0.499872 0.249936)
			(stroke
				(width 0.1)
				(type default)
			)
			(layer "F.Fab")
		)
		(pad "A" smd rect
			(at -0.47498 0)
			(size 0.6096 0.7112)
			(layers "F.Cu" "F.Mask" "F.Paste")
			(net "LED_RST_PLD_CPU0_DRAM_EF_N")
		)
		(pad "C" smd rect
			(at 0.47498 0)
			(size 0.6096 0.7112)
			(layers "F.Cu" "F.Mask" "F.Paste")
			(net "LED_RST_PLD_CPU0_DRAM_EF_N_D")
		)
	)
	(footprint ""
		(layer "F.Cu")
		(at 326.311768 -402.371052 -90)
		(property "Reference" "C1565"
			(at 0 0 270)
			(layer "F.SilkS")
			(hide yes)
			(effects
				(font
					(size 1.27 1.27)
				)
			)
		)
		(property "Value" ""
			(at 0 0 270)
			(layer "F.Fab")
			(effects
				(font
					(size 1.27 1.27)
				)
			)
		)
		(duplicate_pad_numbers_are_jumpers no)
		(fp_line
			(start -0.299974 0.150114)
			(end -0.299974 -0.150114)
			(stroke
				(width 0.1)
				(type default)
			)
			(layer "F.Fab")
		)
		(fp_line
			(start 0.299974 0.150114)
			(end -0.299974 0.150114)
			(stroke
				(width 0.1)
				(type default)
			)
			(layer "F.Fab")
		)
		(fp_line
			(start -0.299974 -0.150114)
			(end 0.299974 -0.150114)
			(stroke
				(width 0.1)
				(type default)
			)
			(layer "F.Fab")
		)
		(fp_line
			(start 0.299974 -0.150114)
			(end 0.299974 0.150114)
			(stroke
				(width 0.1)
				(type default)
			)
			(layer "F.Fab")
		)
		(pad "1" smd rect
			(at -0.2667 0 270)
			(size 0.3048 0.381)
			(layers "F.Cu" "F.Mask" "F.Paste")
			(net "P5E_CPU0_PE4_TX_C_DP<7>")
		)
		(pad "2" smd rect
			(at 0.2667 0 270)
			(size 0.3048 0.381)
			(layers "F.Cu" "F.Mask" "F.Paste")
			(net "P5E_CPU0_PE4_TX_DP<7>")
		)
	)
	(footprint ""
		(layer "F.Cu")
		(at 78.160626 -152.226772 180)
		(property "Reference" "R674"
			(at 0 0 180)
			(layer "F.SilkS")
			(hide yes)
			(effects
				(font
					(size 1.27 1.27)
				)
			)
		)
		(property "Value" ""
			(at 0 0 180)
			(layer "F.Fab")
			(effects
				(font
					(size 1.27 1.27)
				)
			)
		)
		(duplicate_pad_numbers_are_jumpers no)
		(fp_line
			(start 0.7874 0.4064)
			(end -0.7874 0.4064)
			(stroke
				(width 0.1524)
				(type default)
			)
			(layer "F.SilkS")
		)
		(fp_line
			(start 0.7874 -0.4064)
			(end 0.7874 0.4064)
			(stroke
				(width 0.1524)
				(type default)
			)
			(layer "F.SilkS")
		)
		(fp_line
			(start -0.7874 0.4064)
			(end -0.7874 -0.4064)
			(stroke
				(width 0.1524)
				(type default)
			)
			(layer "F.SilkS")
		)
		(fp_line
			(start -0.7874 -0.4064)
			(end 0.7874 -0.4064)
			(stroke
				(width 0.1524)
				(type default)
			)
			(layer "F.SilkS")
		)
		(fp_line
			(start 0.67945 0.3048)
			(end 0.120396 0.3048)
			(stroke
				(width 0.1)
				(type default)
			)
			(layer "F.Fab")
		)
		(fp_line
			(start 0.67945 -0.3048)
			(end 0.67945 0.3048)
			(stroke
				(width 0.1)
				(type default)
			)
			(layer "F.Fab")
		)
		(fp_line
			(start 0.12065 -0.2794)
			(end 0.12065 -0.3048)
			(stroke
				(width 0.1)
				(type default)
			)
			(layer "F.Fab")
		)
		(fp_line
			(start 0.12065 -0.3048)
			(end 0.67945 -0.3048)
			(stroke
				(width 0.1)
				(type default)
			)
			(layer "F.Fab")
		)
		(fp_line
			(start 0.120396 0.3048)
			(end 0.120396 0.2794)
			(stroke
				(width 0.1)
				(type default)
			)
			(layer "F.Fab")
		)
		(fp_line
			(start 0.120396 0.2794)
			(end -0.12065 0.2794)
			(stroke
				(width 0.1)
				(type default)
			)
			(layer "F.Fab")
		)
		(fp_line
			(start -0.12065 0.3048)
			(end -0.67945 0.3048)
			(stroke
				(width 0.1)
				(type default)
			)
			(layer "F.Fab")
		)
		(fp_line
			(start -0.12065 0.2794)
			(end -0.12065 0.3048)
			(stroke
				(width 0.1)
				(type default)
			)
			(layer "F.Fab")
		)
		(fp_line
			(start -0.12065 -0.2794)
			(end 0.12065 -0.2794)
			(stroke
				(width 0.1)
				(type default)
			)
			(layer "F.Fab")
		)
		(fp_line
			(start -0.12065 -0.305054)
			(end -0.12065 -0.2794)
			(stroke
				(width 0.1)
				(type default)
			)
			(layer "F.Fab")
		)
		(fp_line
			(start -0.67945 0.3048)
			(end -0.67945 -0.305054)
			(stroke
				(width 0.1)
				(type default)
			)
			(layer "F.Fab")
		)
		(fp_line
			(start -0.67945 -0.305054)
			(end -0.12065 -0.305054)
			(stroke
				(width 0.1)
				(type default)
			)
			(layer "F.Fab")
		)
		(pad "1" smd circle
			(at -0.40005 0 180)
			(size 0 0)
			(layers "F.Cu" "F.Mask" "F.Paste")
			(net "I3C_SPD_DDRABCD_CPU1_LVC1_R_SCL")
		)
		(pad "2" smd circle
			(at 0.40005 0 180)
			(size 0 0)
			(layers "F.Cu" "F.Mask" "F.Paste")
			(net "I3C_SPD_DDRABCD_CPU1_LVC1_SCL")
		)
	)
)
